(kicad_pcb
	(version 20260206)
	(generator "pcbnew")
	(generator_version "10.0")
	(general
		(thickness 1.6)
		(legacy_teardrops no)
	)
	(paper "A4")
	(title_block
		(title "04192023_DAF0TMB3IC0_F0TG_MB_C_brd_V02_OCP.brd")
		(comment 1 "Grand Teton / footprints 4604-4610 of 8354")
	)
	(layers
		(0 "F.Cu" signal "TOP")
		(4 "In1.Cu" signal "GND")
		(6 "In2.Cu" signal "IN1")
		(8 "In3.Cu" signal "GND1")
		(10 "In4.Cu" signal "IN2")
		(12 "In5.Cu" signal "GND2")
		(14 "In6.Cu" signal "IN3")
		(16 "In7.Cu" signal "GND3")
		(18 "In8.Cu" signal "VCC")
		(20 "In9.Cu" signal "VCC1")
		(22 "In10.Cu" signal "GND4")
		(24 "In11.Cu" signal "IN4")
		(26 "In12.Cu" signal "GND5")
		(28 "In13.Cu" signal "IN5")
		(30 "In14.Cu" signal "GND6")
		(32 "In15.Cu" signal "IN6")
		(34 "In16.Cu" signal "GND7")
		(2 "B.Cu" signal "BOTTOM")
		(9 "F.Adhes" user "F.Adhesive")
		(11 "B.Adhes" user "B.Adhesive")
		(13 "F.Paste" user "Package Geometry/Pastemask Top")
		(15 "B.Paste" user "Package Geometry/Pastemask Bottom")
		(5 "F.SilkS" user "Ref Des/Silkscreen Top")
		(7 "B.SilkS" user "Ref Des/Silkscreen Bottom")
		(1 "F.Mask" user "Board Geometry/Soldermask Top")
		(3 "B.Mask" user "Board Geometry/Soldermask Bottom")
		(17 "Dwgs.User" user "User.Drawings")
		(19 "Cmts.User" user "User.Comments")
		(21 "Eco1.User" user "User.Eco1")
		(23 "Eco2.User" user "User.Eco2")
		(25 "Edge.Cuts" user "Board Geometry/Outline")
		(27 "Margin" user)
		(31 "F.CrtYd" user "Package Geometry/Place Bound Top")
		(29 "B.CrtYd" user "Package Geometry/Place Bound Bottom")
		(35 "F.Fab" user "Ref Des/Assembly Top")
		(33 "B.Fab" user "Ref Des/Assembly Bottom")
	)
	(footprint ""
		(layer "F.Cu")
		(at 84.978494 -177.88636 -90)
		(property "Reference" "PC254_1"
			(at 0 0 270)
			(layer "F.SilkS")
			(hide yes)
			(effects
				(font
					(size 1.27 1.27)
				)
			)
		)
		(property "Value" ""
			(at 0 0 270)
			(layer "F.Fab")
			(effects
				(font
					(size 1.27 1.27)
				)
			)
		)
		(duplicate_pad_numbers_are_jumpers no)
		(fp_line
			(start -0.7874 0.4064)
			(end -0.7874 -0.4064)
			(stroke
				(width 0.1524)
				(type default)
			)
			(layer "F.SilkS")
		)
		(fp_line
			(start 0.7874 0.4064)
			(end -0.7874 0.4064)
			(stroke
				(width 0.1524)
				(type default)
			)
			(layer "F.SilkS")
		)
		(fp_line
			(start -0.7874 -0.4064)
			(end 0.7874 -0.4064)
			(stroke
				(width 0.1524)
				(type default)
			)
			(layer "F.SilkS")
		)
		(fp_line
			(start 0.7874 -0.4064)
			(end 0.7874 0.4064)
			(stroke
				(width 0.1524)
				(type default)
			)
			(layer "F.SilkS")
		)
		(fp_line
			(start -0.67945 0.3048)
			(end -0.67945 -0.305054)
			(stroke
				(width 0.1)
				(type default)
			)
			(layer "F.Fab")
		)
		(fp_line
			(start -0.12065 0.3048)
			(end -0.67945 0.3048)
			(stroke
				(width 0.1)
				(type default)
			)
			(layer "F.Fab")
		)
		(fp_line
			(start 0.120396 0.3048)
			(end 0.120396 0.2794)
			(stroke
				(width 0.1)
				(type default)
			)
			(layer "F.Fab")
		)
		(fp_line
			(start 0.67945 0.3048)
			(end 0.120396 0.3048)
			(stroke
				(width 0.1)
				(type default)
			)
			(layer "F.Fab")
		)
		(fp_line
			(start -0.12065 0.2794)
			(end -0.12065 0.3048)
			(stroke
				(width 0.1)
				(type default)
			)
			(layer "F.Fab")
		)
		(fp_line
			(start 0.120396 0.2794)
			(end -0.12065 0.2794)
			(stroke
				(width 0.1)
				(type default)
			)
			(layer "F.Fab")
		)
		(fp_line
			(start -0.12065 -0.2794)
			(end 0.12065 -0.2794)
			(stroke
				(width 0.1)
				(type default)
			)
			(layer "F.Fab")
		)
		(fp_line
			(start 0.12065 -0.2794)
			(end 0.12065 -0.3048)
			(stroke
				(width 0.1)
				(type default)
			)
			(layer "F.Fab")
		)
		(fp_line
			(start 0.12065 -0.3048)
			(end 0.67945 -0.3048)
			(stroke
				(width 0.1)
				(type default)
			)
			(layer "F.Fab")
		)
		(fp_line
			(start 0.67945 -0.3048)
			(end 0.67945 0.3048)
			(stroke
				(width 0.1)
				(type default)
			)
			(layer "F.Fab")
		)
		(fp_line
			(start -0.67945 -0.305054)
			(end -0.12065 -0.305054)
			(stroke
				(width 0.1)
				(type default)
			)
			(layer "F.Fab")
		)
		(fp_line
			(start -0.12065 -0.305054)
			(end -0.12065 -0.2794)
			(stroke
				(width 0.1)
				(type default)
			)
			(layer "F.Fab")
		)
		(pad "1" smd circle
			(at -0.40005 0 270)
			(size 0 0)
			(layers "F.Cu" "F.Mask" "F.Paste")
			(net "PVDDCR_CPU0_P1_VCCS")
		)
		(pad "2" smd circle
			(at 0.40005 0 270)
			(size 0 0)
			(layers "F.Cu" "F.Mask" "F.Paste")
			(net "GND")
		)
	)
	(footprint ""
		(layer "F.Cu")
		(at 433.756562 -355.743764 -90)
		(property "Reference" "PC218"
			(at 0 0 270)
			(layer "F.SilkS")
			(hide yes)
			(effects
				(font
					(size 1.27 1.27)
				)
			)
		)
		(property "Value" ""
			(at 0 0 270)
			(layer "F.Fab")
			(effects
				(font
					(size 1.27 1.27)
				)
			)
		)
		(duplicate_pad_numbers_are_jumpers no)
		(fp_line
			(start -0.7874 0.4064)
			(end -0.7874 -0.4064)
			(stroke
				(width 0.1524)
				(type default)
			)
			(layer "F.SilkS")
		)
		(fp_line
			(start 0.7874 0.4064)
			(end -0.7874 0.4064)
			(stroke
				(width 0.1524)
				(type default)
			)
			(layer "F.SilkS")
		)
		(fp_line
			(start -0.7874 -0.4064)
			(end 0.7874 -0.4064)
			(stroke
				(width 0.1524)
				(type default)
			)
			(layer "F.SilkS")
		)
		(fp_line
			(start 0.7874 -0.4064)
			(end 0.7874 0.4064)
			(stroke
				(width 0.1524)
				(type default)
			)
			(layer "F.SilkS")
		)
		(fp_line
			(start -0.67945 0.3048)
			(end -0.67945 -0.305054)
			(stroke
				(width 0.1)
				(type default)
			)
			(layer "F.Fab")
		)
		(fp_line
			(start -0.12065 0.3048)
			(end -0.67945 0.3048)
			(stroke
				(width 0.1)
				(type default)
			)
			(layer "F.Fab")
		)
		(fp_line
			(start 0.120396 0.3048)
			(end 0.120396 0.2794)
			(stroke
				(width 0.1)
				(type default)
			)
			(layer "F.Fab")
		)
		(fp_line
			(start 0.67945 0.3048)
			(end 0.120396 0.3048)
			(stroke
				(width 0.1)
				(type default)
			)
			(layer "F.Fab")
		)
		(fp_line
			(start -0.12065 0.2794)
			(end -0.12065 0.3048)
			(stroke
				(width 0.1)
				(type default)
			)
			(layer "F.Fab")
		)
		(fp_line
			(start 0.120396 0.2794)
			(end -0.12065 0.2794)
			(stroke
				(width 0.1)
				(type default)
			)
			(layer "F.Fab")
		)
		(fp_line
			(start -0.12065 -0.2794)
			(end 0.12065 -0.2794)
			(stroke
				(width 0.1)
				(type default)
			)
			(layer "F.Fab")
		)
		(fp_line
			(start 0.12065 -0.2794)
			(end 0.12065 -0.3048)
			(stroke
				(width 0.1)
				(type default)
			)
			(layer "F.Fab")
		)
		(fp_line
			(start 0.12065 -0.3048)
			(end 0.67945 -0.3048)
			(stroke
				(width 0.1)
				(type default)
			)
			(layer "F.Fab")
		)
		(fp_line
			(start 0.67945 -0.3048)
			(end 0.67945 0.3048)
			(stroke
				(width 0.1)
				(type default)
			)
			(layer "F.Fab")
		)
		(fp_line
			(start -0.67945 -0.305054)
			(end -0.12065 -0.305054)
			(stroke
				(width 0.1)
				(type default)
			)
			(layer "F.Fab")
		)
		(fp_line
			(start -0.12065 -0.305054)
			(end -0.12065 -0.2794)
			(stroke
				(width 0.1)
				(type default)
			)
			(layer "F.Fab")
		)
		(pad "1" smd circle
			(at -0.40005 0 270)
			(size 0 0)
			(layers "F.Cu" "F.Mask" "F.Paste")
			(net "SW_PVDD11_S3_P0_BOOT2_RC")
		)
		(pad "2" smd circle
			(at 0.40005 0 270)
			(size 0 0)
			(layers "F.Cu" "F.Mask" "F.Paste")
			(net "SW_PVDD11_S3_P0_PH2")
		)
	)
	(footprint ""
		(layer "F.Cu")
		(at 27.487626 -428.755302 180)
		(property "Reference" "R6158"
			(at 0 0 180)
			(layer "F.SilkS")
			(hide yes)
			(effects
				(font
					(size 1.27 1.27)
				)
			)
		)
		(property "Value" ""
			(at 0 0 180)
			(layer "F.Fab")
			(effects
				(font
					(size 1.27 1.27)
				)
			)
		)
		(duplicate_pad_numbers_are_jumpers no)
		(fp_line
			(start 0.32512 0.175006)
			(end -0.32512 0.175006)
			(stroke
				(width 0.1)
				(type default)
			)
			(layer "F.Fab")
		)
		(fp_line
			(start 0.32512 -0.175006)
			(end 0.32512 0.175006)
			(stroke
				(width 0.1)
				(type default)
			)
			(layer "F.Fab")
		)
		(fp_line
			(start -0.32512 0.175006)
			(end -0.32512 -0.175006)
			(stroke
				(width 0.1)
				(type default)
			)
			(layer "F.Fab")
		)
		(fp_line
			(start -0.32512 -0.175006)
			(end 0.32512 -0.175006)
			(stroke
				(width 0.1)
				(type default)
			)
			(layer "F.Fab")
		)
		(pad "1" smd rect
			(at -0.2667 0 180)
			(size 0.3048 0.381)
			(layers "F.Cu" "F.Mask" "F.Paste")
			(net "P2E_MB_BMC_RX_DP<0>")
		)
		(pad "2" smd rect
			(at 0.2667 0)
			(size 0.3048 0.381)
			(layers "F.Cu" "F.Mask" "F.Paste")
			(net "P2E_MB_BMC_RX_R2_DP<0>")
		)
	)
	(footprint ""
		(layer "F.Cu")
		(at 33.198054 -349.386398 90)
		(property "Reference" "PC617"
			(at 0 0 90)
			(layer "F.SilkS")
			(hide yes)
			(effects
				(font
					(size 1.27 1.27)
				)
			)
		)
		(property "Value" ""
			(at 0 0 90)
			(layer "F.Fab")
			(effects
				(font
					(size 1.27 1.27)
				)
			)
		)
		(duplicate_pad_numbers_are_jumpers no)
		(fp_line
			(start 0.7874 -0.4064)
			(end 0.7874 0.4064)
			(stroke
				(width 0.1524)
				(type default)
			)
			(layer "F.SilkS")
		)
		(fp_line
			(start -0.7874 -0.4064)
			(end 0.7874 -0.4064)
			(stroke
				(width 0.1524)
				(type default)
			)
			(layer "F.SilkS")
		)
		(fp_line
			(start 0.7874 0.4064)
			(end 0.447802 0.4064)
			(stroke
				(width 0.1524)
				(type default)
			)
			(layer "F.SilkS")
		)
		(fp_line
			(start -0.237998 0.4064)
			(end -0.7874 0.4064)
			(stroke
				(width 0.1524)
				(type default)
			)
			(layer "F.SilkS")
		)
		(fp_line
			(start -0.7874 0.4064)
			(end -0.7874 -0.4064)
			(stroke
				(width 0.1524)
				(type default)
			)
			(layer "F.SilkS")
		)
		(fp_line
			(start -0.12065 -0.305054)
			(end -0.12065 -0.2794)
			(stroke
				(width 0.1)
				(type default)
			)
			(layer "F.Fab")
		)
		(fp_line
			(start -0.67945 -0.305054)
			(end -0.12065 -0.305054)
			(stroke
				(width 0.1)
				(type default)
			)
			(layer "F.Fab")
		)
		(fp_line
			(start 0.67945 -0.3048)
			(end 0.67945 0.3048)
			(stroke
				(width 0.1)
				(type default)
			)
			(layer "F.Fab")
		)
		(fp_line
			(start 0.12065 -0.3048)
			(end 0.67945 -0.3048)
			(stroke
				(width 0.1)
				(type default)
			)
			(layer "F.Fab")
		)
		(fp_line
			(start 0.12065 -0.2794)
			(end 0.12065 -0.3048)
			(stroke
				(width 0.1)
				(type default)
			)
			(layer "F.Fab")
		)
		(fp_line
			(start -0.12065 -0.2794)
			(end 0.12065 -0.2794)
			(stroke
				(width 0.1)
				(type default)
			)
			(layer "F.Fab")
		)
		(fp_line
			(start 0.120396 0.2794)
			(end -0.12065 0.2794)
			(stroke
				(width 0.1)
				(type default)
			)
			(layer "F.Fab")
		)
		(fp_line
			(start -0.12065 0.2794)
			(end -0.12065 0.3048)
			(stroke
				(width 0.1)
				(type default)
			)
			(layer "F.Fab")
		)
		(fp_line
			(start 0.67945 0.3048)
			(end 0.120396 0.3048)
			(stroke
				(width 0.1)
				(type default)
			)
			(layer "F.Fab")
		)
		(fp_line
			(start 0.120396 0.3048)
			(end 0.120396 0.2794)
			(stroke
				(width 0.1)
				(type default)
			)
			(layer "F.Fab")
		)
		(fp_line
			(start -0.12065 0.3048)
			(end -0.67945 0.3048)
			(stroke
				(width 0.1)
				(type default)
			)
			(layer "F.Fab")
		)
		(fp_line
			(start -0.67945 0.3048)
			(end -0.67945 -0.305054)
			(stroke
				(width 0.1)
				(type default)
			)
			(layer "F.Fab")
		)
		(pad "1" smd circle
			(at -0.40005 0 90)
			(size 0 0)
			(layers "F.Cu" "F.Mask" "F.Paste")
			(net "PVDDIO_P1_VCC3")
		)
		(pad "2" smd circle
			(at 0.40005 0 90)
			(size 0 0)
			(layers "F.Cu" "F.Mask" "F.Paste")
			(net "GND")
		)
	)
	(footprint ""
		(layer "F.Cu")
		(at 18.828258 -427.580298 90)
		(property "Reference" "R6160"
			(at 0 0 90)
			(layer "F.SilkS")
			(hide yes)
			(effects
				(font
					(size 1.27 1.27)
				)
			)
		)
		(property "Value" ""
			(at 0 0 90)
			(layer "F.Fab")
			(effects
				(font
					(size 1.27 1.27)
				)
			)
		)
		(duplicate_pad_numbers_are_jumpers no)
		(fp_line
			(start 0.7874 -0.4064)
			(end 0.7874 0.4064)
			(stroke
				(width 0.1524)
				(type default)
			)
			(layer "F.SilkS")
		)
		(fp_line
			(start -0.7874 -0.4064)
			(end 0.7874 -0.4064)
			(stroke
				(width 0.1524)
				(type default)
			)
			(layer "F.SilkS")
		)
		(fp_line
			(start 0.7874 0.4064)
			(end -0.7874 0.4064)
			(stroke
				(width 0.1524)
				(type default)
			)
			(layer "F.SilkS")
		)
		(fp_line
			(start -0.7874 0.4064)
			(end -0.7874 -0.4064)
			(stroke
				(width 0.1524)
				(type default)
			)
			(layer "F.SilkS")
		)
		(fp_line
			(start -0.12065 -0.305054)
			(end -0.12065 -0.2794)
			(stroke
				(width 0.1)
				(type default)
			)
			(layer "F.Fab")
		)
		(fp_line
			(start -0.67945 -0.305054)
			(end -0.12065 -0.305054)
			(stroke
				(width 0.1)
				(type default)
			)
			(layer "F.Fab")
		)
		(fp_line
			(start 0.67945 -0.3048)
			(end 0.67945 0.3048)
			(stroke
				(width 0.1)
				(type default)
			)
			(layer "F.Fab")
		)
		(fp_line
			(start 0.12065 -0.3048)
			(end 0.67945 -0.3048)
			(stroke
				(width 0.1)
				(type default)
			)
			(layer "F.Fab")
		)
		(fp_line
			(start 0.12065 -0.2794)
			(end 0.12065 -0.3048)
			(stroke
				(width 0.1)
				(type default)
			)
			(layer "F.Fab")
		)
		(fp_line
			(start -0.12065 -0.2794)
			(end 0.12065 -0.2794)
			(stroke
				(width 0.1)
				(type default)
			)
			(layer "F.Fab")
		)
		(fp_line
			(start 0.120396 0.2794)
			(end -0.12065 0.2794)
			(stroke
				(width 0.1)
				(type default)
			)
			(layer "F.Fab")
		)
		(fp_line
			(start -0.12065 0.2794)
			(end -0.12065 0.3048)
			(stroke
				(width 0.1)
				(type default)
			)
			(layer "F.Fab")
		)
		(fp_line
			(start 0.67945 0.3048)
			(end 0.120396 0.3048)
			(stroke
				(width 0.1)
				(type default)
			)
			(layer "F.Fab")
		)
		(fp_line
			(start 0.120396 0.3048)
			(end 0.120396 0.2794)
			(stroke
				(width 0.1)
				(type default)
			)
			(layer "F.Fab")
		)
		(fp_line
			(start -0.12065 0.3048)
			(end -0.67945 0.3048)
			(stroke
				(width 0.1)
				(type default)
			)
			(layer "F.Fab")
		)
		(fp_line
			(start -0.67945 0.3048)
			(end -0.67945 -0.305054)
			(stroke
				(width 0.1)
				(type default)
			)
			(layer "F.Fab")
		)
		(pad "1" smd circle
			(at -0.40005 0 90)
			(size 0 0)
			(layers "F.Cu" "F.Mask" "F.Paste")
			(net "PD_P2E_BUF2_ENSMB")
		)
		(pad "2" smd circle
			(at 0.40005 0 90)
			(size 0 0)
			(layers "F.Cu" "F.Mask" "F.Paste")
			(net "GND")
		)
	)
	(footprint ""
		(layer "F.Cu")
		(at 122.952002 -78.732888 -90)
		(property "Reference" "PR6005"
			(at 0 0 270)
			(layer "F.SilkS")
			(hide yes)
			(effects
				(font
					(size 1.27 1.27)
				)
			)
		)
		(property "Value" ""
			(at 0 0 270)
			(layer "F.Fab")
			(effects
				(font
					(size 1.27 1.27)
				)
			)
		)
		(duplicate_pad_numbers_are_jumpers no)
		(fp_line
			(start -0.7874 0.4064)
			(end -0.7874 -0.4064)
			(stroke
				(width 0.1524)
				(type default)
			)
			(layer "F.SilkS")
		)
		(fp_line
			(start 0.7874 0.4064)
			(end -0.7874 0.4064)
			(stroke
				(width 0.1524)
				(type default)
			)
			(layer "F.SilkS")
		)
		(fp_line
			(start -0.7874 -0.4064)
			(end 0.7874 -0.4064)
			(stroke
				(width 0.1524)
				(type default)
			)
			(layer "F.SilkS")
		)
		(fp_line
			(start 0.7874 -0.4064)
			(end 0.7874 0.4064)
			(stroke
				(width 0.1524)
				(type default)
			)
			(layer "F.SilkS")
		)
		(fp_line
			(start -0.67945 0.3048)
			(end -0.67945 -0.305054)
			(stroke
				(width 0.1)
				(type default)
			)
			(layer "F.Fab")
		)
		(fp_line
			(start -0.12065 0.3048)
			(end -0.67945 0.3048)
			(stroke
				(width 0.1)
				(type default)
			)
			(layer "F.Fab")
		)
		(fp_line
			(start 0.120396 0.3048)
			(end 0.120396 0.2794)
			(stroke
				(width 0.1)
				(type default)
			)
			(layer "F.Fab")
		)
		(fp_line
			(start 0.67945 0.3048)
			(end 0.120396 0.3048)
			(stroke
				(width 0.1)
				(type default)
			)
			(layer "F.Fab")
		)
		(fp_line
			(start -0.12065 0.2794)
			(end -0.12065 0.3048)
			(stroke
				(width 0.1)
				(type default)
			)
			(layer "F.Fab")
		)
		(fp_line
			(start 0.120396 0.2794)
			(end -0.12065 0.2794)
			(stroke
				(width 0.1)
				(type default)
			)
			(layer "F.Fab")
		)
		(fp_line
			(start -0.12065 -0.2794)
			(end 0.12065 -0.2794)
			(stroke
				(width 0.1)
				(type default)
			)
			(layer "F.Fab")
		)
		(fp_line
			(start 0.12065 -0.2794)
			(end 0.12065 -0.3048)
			(stroke
				(width 0.1)
				(type default)
			)
			(layer "F.Fab")
		)
		(fp_line
			(start 0.12065 -0.3048)
			(end 0.67945 -0.3048)
			(stroke
				(width 0.1)
				(type default)
			)
			(layer "F.Fab")
		)
		(fp_line
			(start 0.67945 -0.3048)
			(end 0.67945 0.3048)
			(stroke
				(width 0.1)
				(type default)
			)
			(layer "F.Fab")
		)
		(fp_line
			(start -0.67945 -0.305054)
			(end -0.12065 -0.305054)
			(stroke
				(width 0.1)
				(type default)
			)
			(layer "F.Fab")
		)
		(fp_line
			(start -0.12065 -0.305054)
			(end -0.12065 -0.2794)
			(stroke
				(width 0.1)
				(type default)
			)
			(layer "F.Fab")
		)
		(pad "1" smd circle
			(at -0.40005 0 270)
			(size 0 0)
			(layers "F.Cu" "F.Mask" "F.Paste")
			(net "GND")
		)
		(pad "2" smd circle
			(at 0.40005 0 270)
			(size 0 0)
			(layers "F.Cu" "F.Mask" "F.Paste")
			(net "P1V2_AUX_MODE")
		)
	)
	(footprint ""
		(layer "F.Cu")
		(at 283.820362 -337.399122)
		(property "Reference" "PL21"
			(at -2.607056 -16.014446 0)
			(unlocked yes)
			(layer "F.SilkS")
			(effects
				(font
					(size 0.7874 0.5842)
					(thickness 0.1524)
				)
				(justify left)
			)
		)
		(property "Value" ""
			(at 0 0 0)
			(layer "F.Fab")
			(effects
				(font
					(size 1.27 1.27)
				)
			)
		)
		(duplicate_pad_numbers_are_jumpers no)
		(fp_line
			(start -3.750056 -5.500116)
			(end -2.393442 -5.500116)
			(stroke
				(width 0.1524)
				(type default)
			)
			(layer "F.SilkS")
		)
		(fp_line
			(start -3.750056 5.500116)
			(end -3.750056 -5.500116)
			(stroke
				(width 0.1524)
				(type default)
			)
			(layer "F.SilkS")
		)
		(fp_line
			(start -2.393442 5.500116)
			(end -3.750056 5.500116)
			(stroke
				(width 0.1524)
				(type default)
			)
			(layer "F.SilkS")
		)
		(fp_line
			(start 2.393442 5.500116)
			(end 3.750056 5.500116)
			(stroke
				(width 0.1524)
				(type default)
			)
			(layer "F.SilkS")
		)
		(fp_line
			(start 3.750056 -5.500116)
			(end 2.393442 -5.500116)
			(stroke
				(width 0.1524)
				(type default)
			)
			(layer "F.SilkS")
		)
		(fp_line
			(start 3.750056 5.500116)
			(end 3.750056 -5.500116)
			(stroke
				(width 0.1524)
				(type default)
			)
			(layer "F.SilkS")
		)
		(fp_poly
			(pts
				(xy -3.9116 -4.249928) (xy -4.3434 -4.034028) (xy -4.3434 -4.465828)
			)
			(stroke
				(width 0)
				(type default)
			)
			(fill yes)
			(layer "F.SilkS")
		)
		(fp_line
			(start -3.750056 -5.500116)
			(end -3.750056 5.500116)
			(stroke
				(width 0.1)
				(type default)
			)
			(layer "F.Fab")
		)
		(fp_line
			(start -3.750056 5.500116)
			(end 3.750056 5.500116)
			(stroke
				(width 0.1)
				(type default)
			)
			(layer "F.Fab")
		)
		(fp_line
			(start 3.750056 -5.500116)
			(end -3.750056 -5.500116)
			(stroke
				(width 0.1)
				(type default)
			)
			(layer "F.Fab")
		)
		(fp_line
			(start 3.750056 5.500116)
			(end 3.750056 -5.500116)
			(stroke
				(width 0.1)
				(type default)
			)
			(layer "F.Fab")
		)
		(fp_poly
			(pts
				(xy -4.9276 -4.757928) (xy -4.9276 -3.741928) (xy -3.9116 -4.249928)
			)
			(stroke
				(width 0)
				(type default)
			)
			(fill yes)
			(layer "F.Fab")
		)
		(pad "1" smd rect
			(at 0 -4.249928 270)
			(size 2.413 4.5212)
			(layers "F.Cu" "F.Mask" "F.Paste")
			(net "SW_PVDDIO_P0_SW3")
		)
		(pad "2" smd rect
			(at 0 -1.175004 270)
			(size 1.3716 4.5212)
			(layers "F.Cu" "F.Mask" "F.Paste")
			(net "IND_PVDDIO_P0_CPL4")
		)
		(pad "3" smd rect
			(at 0 1.175004 270)
			(size 1.3716 4.5212)
			(layers "F.Cu" "F.Mask" "F.Paste")
			(net "IND_PVDDIO_P0_CPL3")
		)
		(pad "4" smd rect
			(at 0 4.249928 270)
			(size 2.413 4.5212)
			(layers "F.Cu" "F.Mask" "F.Paste")
			(net "PVDDIO_P0")
		)
	)
)
